# S9S_MB_2U (Grand Teton) — schematic netlist excerpt (pin names and nets, part order shuffled) for the footprints in the layout excerpt that follows; sources: Cadence DE-HDL packaged netlist, KiCad conversion of 03242023_DA0F0TMBIJ0_F0T_Motherboard_J_brd_V01_OCP.brd

C2458  Q_CAP  0.1UF 25V 10% EMPTY  pkg 0402  page 305 : A = P3V3_AUX ; B = GND
PL43  Q_INDUCTOR  100NH/16A IND  pkg SMLF  page 289 : \1\ = P12V_AUX ; \2\ = SW_P12V_PVCCFA_EHV_FIVRA_CPU1_L

(kicad_pcb
	(version 20260206)
	(generator "pcbnew")
	(generator_version "10.0")
	(general
		(thickness 1.6)
		(legacy_teardrops no)
	)
	(paper "A4")
	(title_block
		(title "03242023_DA0F0TMBIJ0_F0T_Motherboard_J_brd_V01_OCP.brd")
		(comment 1 "Grand Teton / footprints 754-755 of 6105")
	)
	(layers
		(0 "F.Cu" signal "TOP")
		(4 "In1.Cu" signal "GND")
		(6 "In2.Cu" signal "IN1")
		(8 "In3.Cu" signal "GND1")
		(10 "In4.Cu" signal "IN2")
		(12 "In5.Cu" signal "GND2")
		(14 "In6.Cu" signal "IN3")
		(16 "In7.Cu" signal "GND3")
		(18 "In8.Cu" signal "VCC")
		(20 "In9.Cu" signal "VCC1")
		(22 "In10.Cu" signal "GND4")
		(24 "In11.Cu" signal "IN4")
		(26 "In12.Cu" signal "GND5")
		(28 "In13.Cu" signal "IN5")
		(30 "In14.Cu" signal "GND6")
		(32 "In15.Cu" signal "IN6")
		(34 "In16.Cu" signal "GND7")
		(2 "B.Cu" signal "BOTTOM")
		(9 "F.Adhes" user "F.Adhesive")
		(11 "B.Adhes" user "B.Adhesive")
		(13 "F.Paste" user "Package Geometry/Pastemask Top")
		(15 "B.Paste" user "Package Geometry/Pastemask Bottom")
		(5 "F.SilkS" user "Ref Des/Silkscreen Top")
		(7 "B.SilkS" user "Ref Des/Silkscreen Bottom")
		(1 "F.Mask" user "Board Geometry/Soldermask Top")
		(3 "B.Mask" user "Board Geometry/Soldermask Bottom")
		(17 "Dwgs.User" user "User.Drawings")
		(19 "Cmts.User" user "User.Comments")
		(21 "Eco1.User" user "User.Eco1")
		(23 "Eco2.User" user "User.Eco2")
		(25 "Edge.Cuts" user "Board Geometry/Outline")
		(27 "Margin" user)
		(31 "F.CrtYd" user "Package Geometry/Place Bound Top")
		(29 "B.CrtYd" user "Package Geometry/Place Bound Bottom")
		(35 "F.Fab" user "Ref Des/Assembly Top")
		(33 "B.Fab" user "Ref Des/Assembly Bottom")
	)
	(footprint ""
		(layer "F.Cu")
		(at 292.34638 -411.21584)
		(property "Reference" "C2458"
			(at 0 0 0)
			(layer "F.SilkS")
			(hide yes)
			(effects
				(font
					(size 1.27 1.27)
				)
			)
		)
		(property "Value" ""
			(at 0 0 0)
			(layer "F.Fab")
			(effects
				(font
					(size 1.27 1.27)
				)
			)
		)
		(duplicate_pad_numbers_are_jumpers no)
		(fp_line
			(start -0.7874 -0.4064)
			(end 0.7874 -0.4064)
			(stroke
				(width 0.1524)
				(type default)
			)
			(layer "F.SilkS")
		)
		(fp_line
			(start -0.7874 0.4064)
			(end -0.7874 -0.4064)
			(stroke
				(width 0.1524)
				(type default)
			)
			(layer "F.SilkS")
		)
		(fp_line
			(start 0.7874 -0.4064)
			(end 0.7874 0.4064)
			(stroke
				(width 0.1524)
				(type default)
			)
			(layer "F.SilkS")
		)
		(fp_line
			(start 0.7874 0.4064)
			(end -0.7874 0.4064)
			(stroke
				(width 0.1524)
				(type default)
			)
			(layer "F.SilkS")
		)
		(fp_line
			(start -0.67945 -0.305054)
			(end -0.12065 -0.305054)
			(stroke
				(width 0.1)
				(type default)
			)
			(layer "F.Fab")
		)
		(fp_line
			(start -0.67945 0.3048)
			(end -0.67945 -0.305054)
			(stroke
				(width 0.1)
				(type default)
			)
			(layer "F.Fab")
		)
		(fp_line
			(start -0.12065 -0.305054)
			(end -0.12065 -0.2794)
			(stroke
				(width 0.1)
				(type default)
			)
			(layer "F.Fab")
		)
		(fp_line
			(start -0.12065 -0.2794)
			(end 0.12065 -0.2794)
			(stroke
				(width 0.1)
				(type default)
			)
			(layer "F.Fab")
		)
		(fp_line
			(start -0.12065 0.2794)
			(end -0.12065 0.3048)
			(stroke
				(width 0.1)
				(type default)
			)
			(layer "F.Fab")
		)
		(fp_line
			(start -0.12065 0.3048)
			(end -0.67945 0.3048)
			(stroke
				(width 0.1)
				(type default)
			)
			(layer "F.Fab")
		)
		(fp_line
			(start 0.120396 0.2794)
			(end -0.12065 0.2794)
			(stroke
				(width 0.1)
				(type default)
			)
			(layer "F.Fab")
		)
		(fp_line
			(start 0.120396 0.3048)
			(end 0.120396 0.2794)
			(stroke
				(width 0.1)
				(type default)
			)
			(layer "F.Fab")
		)
		(fp_line
			(start 0.12065 -0.3048)
			(end 0.67945 -0.3048)
			(stroke
				(width 0.1)
				(type default)
			)
			(layer "F.Fab")
		)
		(fp_line
			(start 0.12065 -0.2794)
			(end 0.12065 -0.3048)
			(stroke
				(width 0.1)
				(type default)
			)
			(layer "F.Fab")
		)
		(fp_line
			(start 0.67945 -0.3048)
			(end 0.67945 0.3048)
			(stroke
				(width 0.1)
				(type default)
			)
			(layer "F.Fab")
		)
		(fp_line
			(start 0.67945 0.3048)
			(end 0.120396 0.3048)
			(stroke
				(width 0.1)
				(type default)
			)
			(layer "F.Fab")
		)
		(pad "1" smd circle
			(at -0.40005 0)
			(size 0 0)
			(layers "F.Cu" "F.Mask" "F.Paste")
			(net "P3V3_AUX")
		)
		(pad "2" smd circle
			(at 0.40005 0)
			(size 0 0)
			(layers "F.Cu" "F.Mask" "F.Paste")
			(net "GND")
		)
	)
	(footprint ""
		(layer "F.Cu")
		(at 43.60037 -363.251242)
		(property "Reference" "PL43"
			(at 0.233172 -3.211068 0)
			(unlocked yes)
			(layer "F.SilkS")
			(effects
				(font
					(size 0.7874 0.5842)
					(thickness 0.1524)
				)
				(justify left)
			)
		)
		(property "Value" ""
			(at 0 0 0)
			(layer "F.Fab")
			(effects
				(font
					(size 1.27 1.27)
				)
			)
		)
		(duplicate_pad_numbers_are_jumpers no)
		(fp_line
			(start -2.249932 -2.249932)
			(end 2.249932 -2.249932)
			(stroke
				(width 0.1524)
				(type default)
			)
			(layer "F.SilkS")
		)
		(fp_line
			(start -2.249932 -1.3843)
			(end -2.249932 -2.249932)
			(stroke
				(width 0.1524)
				(type default)
			)
			(layer "F.SilkS")
		)
		(fp_line
			(start -2.249932 2.249932)
			(end -2.249932 1.3843)
			(stroke
				(width 0.1524)
				(type default)
			)
			(layer "F.SilkS")
		)
		(fp_line
			(start 2.249932 -2.249932)
			(end 2.249932 -1.3843)
			(stroke
				(width 0.1524)
				(type default)
			)
			(layer "F.SilkS")
		)
		(fp_line
			(start 2.249932 1.3843)
			(end 2.249932 2.249932)
			(stroke
				(width 0.1524)
				(type default)
			)
			(layer "F.SilkS")
		)
		(fp_line
			(start 2.249932 2.249932)
			(end -2.249932 2.249932)
			(stroke
				(width 0.1524)
				(type default)
			)
			(layer "F.SilkS")
		)
		(fp_line
			(start -2.249932 -2.249932)
			(end 2.249932 -2.249932)
			(stroke
				(width 0.1)
				(type default)
			)
			(layer "F.Fab")
		)
		(fp_line
			(start -2.249932 2.249932)
			(end -2.249932 -2.249932)
			(stroke
				(width 0.1)
				(type default)
			)
			(layer "F.Fab")
		)
		(fp_line
			(start 2.249932 -2.249932)
			(end 2.249932 2.249932)
			(stroke
				(width 0.1)
				(type default)
			)
			(layer "F.Fab")
		)
		(fp_line
			(start 2.249932 2.249932)
			(end -2.249932 2.249932)
			(stroke
				(width 0.1)
				(type default)
			)
			(layer "F.Fab")
		)
		(pad "1" smd rect
			(at -1.82499 0)
			(size 1.0668 2.5146)
			(layers "F.Cu" "F.Mask" "F.Paste")
			(net "P12V_AUX")
		)
		(pad "2" smd rect
			(at 1.82499 0)
			(size 1.0668 2.5146)
			(layers "F.Cu" "F.Mask" "F.Paste")
			(net "SW_P12V_PVCCFA_EHV_FIVRA_CPU1_L")
		)
	)
)
